# sdi-mipi-video-converter — KiCad project settings (.kicad_pro: net classes, design rules, text variables)
{
  "board": {
    "3dviewports": [],
    "design_settings": {
      "defaults": {
        "apply_defaults_to_fp_fields": false,
        "apply_defaults_to_fp_shapes": false,
        "apply_defaults_to_fp_text": false,
        "board_outline_line_width": 0.1,
        "copper_line_width": 0.2,
        "copper_text_italic": false,
        "copper_text_size_h": 1.5,
        "copper_text_size_v": 1.5,
        "copper_text_thickness": 0.3,
        "copper_text_upright": false,
        "courtyard_line_width": 0.05,
        "dimension_precision": 4,
        "dimension_units": 3,
        "dimensions": {
          "arrow_length": 1270000,
          "extension_offset": 500000,
          "keep_text_aligned": true,
          "suppress_zeroes": false,
          "text_position": 0,
          "units_format": 1
        },
        "fab_line_width": 0.1,
        "fab_text_italic": false,
        "fab_text_size_h": 1.0,
        "fab_text_size_v": 1.0,
        "fab_text_thickness": 0.15,
        "fab_text_upright": false,
        "other_line_width": 0.15,
        "other_text_italic": false,
        "other_text_size_h": 1.0,
        "other_text_size_v": 1.0,
        "other_text_thickness": 0.15,
        "other_text_upright": false,
        "pads": {
          "drill": 0.1,
          "height": 0.45,
          "width": 0.45
        },
        "silk_line_width": 0.15,
        "silk_text_italic": false,
        "silk_text_size_h": 1.0,
        "silk_text_size_v": 1.0,
        "silk_text_thickness": 0.15,
        "silk_text_upright": false,
        "zones": {
          "45_degree_only": false,
          "min_clearance": 0.1
        }
      },
      "diff_pair_dimensions": [
        {
          "gap": 0.0,
          "via_gap": 0.0,
          "width": 0.0
        }
      ],
      "drc_exclusions": [],
      "meta": {
        "version": 2
      },
      "rule_severities": {
        "annular_width": "error",
        "clearance": "error",
        "connection_width": "warning",
        "copper_edge_clearance": "error",
        "copper_sliver": "warning",
        "courtyards_overlap": "error",
        "creepage": "error",
        "diff_pair_gap_out_of_range": "ignore",
        "diff_pair_uncoupled_length_too_long": "ignore",
        "drill_out_of_range": "ignore",
        "duplicate_footprints": "error",
        "extra_footprint": "error",
        "footprint": "error",
        "footprint_filters_mismatch": "ignore",
        "footprint_symbol_mismatch": "warning",
        "footprint_type_mismatch": "warning",
        "hole_clearance": "error",
        "hole_near_hole": "error",
        "hole_to_hole": "error",
        "holes_co_located": "warning",
        "invalid_outline": "error",
        "isolated_copper": "warning",
        "item_on_disabled_layer": "error",
        "items_not_allowed": "error",
        "length_out_of_range": "error",
        "lib_footprint_issues": "warning",
        "lib_footprint_mismatch": "warning",
        "malformed_courtyard": "error",
        "microvia_drill_out_of_range": "error",
        "mirrored_text_on_front_layer": "warning",
        "missing_courtyard": "ignore",
        "missing_footprint": "error",
        "net_conflict": "error",
        "nonmirrored_text_on_back_layer": "warning",
        "npth_inside_courtyard": "error",
        "padstack": "error",
        "pth_inside_courtyard": "error",
        "shorting_items": "error",
        "silk_edge_clearance": "warning",
        "silk_over_copper": "warning",
        "silk_overlap": "warning",
        "skew_out_of_range": "ignore",
        "solder_mask_bridge": "error",
        "starved_thermal": "error",
        "text_height": "warning",
        "text_on_edge_cuts": "error",
        "text_thickness": "warning",
        "through_hole_pad_without_hole": "error",
        "too_many_vias": "error",
        "track_angle": "error",
        "track_dangling": "error",
        "track_segment_length": "error",
        "track_width": "error",
        "tracks_crossing": "error",
        "unconnected_items": "error",
        "unresolved_variable": "error",
        "via_dangling": "error",
        "zones_intersect": "error"
      },
      "rules": {
        "allow_blind_buried_vias": false,
        "allow_microvias": false,
        "max_error": 0.005,
        "min_clearance": 0.1,
        "min_connection": 0.0,
        "min_copper_edge_clearance": 0.4,
        "min_groove_width": 0.0,
        "min_hole_clearance": 0.2,
        "min_hole_to_hole": 0.25,
        "min_microvia_diameter": 0.2,
        "min_microvia_drill": 0.1,
        "min_resolved_spokes": 2,
        "min_silk_clearance": 0.0,
        "min_text_height": 0.5,
        "min_text_thickness": 0.08,
        "min_through_hole_diameter": 0.2,
        "min_track_width": 0.1,
        "min_via_annular_width": 0.125,
        "min_via_diameter": 0.45,
        "solder_mask_clearance": 0.0,
        "solder_mask_min_width": 0.0,
        "solder_mask_to_copper_clearance": 0.0,
        "use_height_for_length_calcs": true
      },
      "teardrop_options": [
        {
          "td_onpthpad": true,
          "td_onroundshapesonly": false,
          "td_onsmdpad": true,
          "td_ontrackend": false,
          "td_onvia": true
        }
      ],
      "teardrop_parameters": [
        {
          "td_allow_use_two_tracks": true,
          "td_curve_segcount": 1,
          "td_height_ratio": 1.0,
          "td_length_ratio": 0.5,
          "td_maxheight": 2.0,
          "td_maxlen": 1.0,
          "td_on_pad_in_zone": false,
          "td_target_name": "td_round_shape",
          "td_width_to_size_filter_ratio": 0.9
        },
        {
          "td_allow_use_two_tracks": true,
          "td_curve_segcount": 1,
          "td_height_ratio": 1.0,
          "td_length_ratio": 0.5,
          "td_maxheight": 2.0,
          "td_maxlen": 1.0,
          "td_on_pad_in_zone": false,
          "td_target_name": "td_rect_shape",
          "td_width_to_size_filter_ratio": 0.9
        },
        {
          "td_allow_use_two_tracks": true,
          "td_curve_segcount": 1,
          "td_height_ratio": 1.0,
          "td_length_ratio": 0.5,
          "td_maxheight": 2.0,
          "td_maxlen": 1.0,
          "td_on_pad_in_zone": false,
          "td_target_name": "td_track_end",
          "td_width_to_size_filter_ratio": 0.9
        }
      ],
      "track_widths": [
        0.0,
        0.1,
        0.125,
        0.13,
        0.15,
        0.2,
        0.3,
        0.5
      ],
      "tuning_pattern_settings": {
        "diff_pair_defaults": {
          "corner_radius_percentage": 80,
          "corner_style": 1,
          "max_amplitude": 1.0,
          "min_amplitude": 0.2,
          "single_sided": false,
          "spacing": 1.0
        },
        "diff_pair_skew_defaults": {
          "corner_radius_percentage": 80,
          "corner_style": 1,
          "max_amplitude": 1.0,
          "min_amplitude": 0.2,
          "single_sided": false,
          "spacing": 0.6
        },
        "single_track_defaults": {
          "corner_radius_percentage": 80,
          "corner_style": 1,
          "max_amplitude": 1.0,
          "min_amplitude": 0.2,
          "single_sided": false,
          "spacing": 0.6
        }
      },
      "via_dimensions": [
        {
          "diameter": 0.0,
          "drill": 0.0
        },
        {
          "diameter": 0.45,
          "drill": 0.1
        },
        {
          "diameter": 0.45,
          "drill": 0.2
        },
        {
          "diameter": 0.6,
          "drill": 0.25
        }
      ],
      "zones_allow_external_fillets": false,
      "zones_use_no_outline": true
    },
    "ipc2581": {
      "dist": "",
      "distpn": "",
      "internal_id": "",
      "mfg": "",
      "mpn": ""
    },
    "layer_pairs": [],
    "layer_presets": [],
    "viewports": []
  },
  "boards": [],
  "cvpcb": {
    "equivalence_files": []
  },
  "erc": {
    "erc_exclusions": [],
    "meta": {
      "version": 0
    },
    "pin_map": [
      [
        0,
        0,
        0,
        0,
        0,
        0,
        1,
        0,
        0,
        0,
        0,
        2
      ],
      [
        0,
        2,
        0,
        1,
        0,
        0,
        1,
        0,
        2,
        2,
        2,
        2
      ],
      [
        0,
        0,
        0,
        0,
        0,
        0,
        1,
        0,
        1,
        0,
        1,
        2
      ],
      [
        0,
        1,
        0,
        0,
        0,
        0,
        1,
        1,
        2,
        1,
        1,
        2
      ],
      [
        0,
        0,
        0,
        0,
        0,
        0,
        1,
        0,
        0,
        0,
        0,
        2
      ],
      [
        0,
        0,
        0,
        0,
        0,
        0,
        0,
        0,
        0,
        0,
        0,
        2
      ],
      [
        1,
        1,
        1,
        1,
        1,
        0,
        1,
        1,
        1,
        1,
        1,
        2
      ],
      [
        0,
        0,
        0,
        1,
        0,
        0,
        1,
        0,
        0,
        0,
        0,
        2
      ],
      [
        0,
        2,
        1,
        2,
        0,
        0,
        1,
        0,
        2,
        2,
        2,
        2
      ],
      [
        0,
        2,
        0,
        1,
        0,
        0,
        1,
        0,
        2,
        0,
        0,
        2
      ],
      [
        0,
        2,
        1,
        1,
        0,
        0,
        1,
        0,
        2,
        0,
        0,
        2
      ],
      [
        2,
        2,
        2,
        2,
        2,
        2,
        2,
        2,
        2,
        2,
        2,
        2
      ]
    ],
    "rule_severities": {
      "bus_definition_conflict": "error",
      "bus_entry_needed": "error",
      "bus_to_bus_conflict": "error",
      "bus_to_net_conflict": "error",
      "conflicting_netclasses": "error",
      "different_unit_footprint": "error",
      "different_unit_net": "error",
      "duplicate_reference": "error",
      "duplicate_sheet_names": "error",
      "endpoint_off_grid": "warning",
      "extra_units": "error",
      "footprint_filter": "ignore",
      "footprint_link_issues": "warning",
      "four_way_junction": "ignore",
      "global_label_dangling": "warning",
      "hier_label_mismatch": "error",
      "label_dangling": "error",
      "label_multiple_wires": "warning",
      "lib_symbol_issues": "warning",
      "lib_symbol_mismatch": "warning",
      "missing_bidi_pin": "warning",
      "missing_input_pin": "warning",
      "missing_power_pin": "error",
      "missing_unit": "warning",
      "multiple_net_names": "warning",
      "net_not_bus_member": "warning",
      "no_connect_connected": "ignore",
      "no_connect_dangling": "warning",
      "pin_not_connected": "error",
      "pin_not_driven": "ignore",
      "pin_to_pin": "ignore",
      "power_pin_not_driven": "ignore",
      "same_local_global_label": "warning",
      "similar_label_and_power": "warning",
      "similar_labels": "warning",
      "similar_power": "warning",
      "simulation_model_issue": "ignore",
      "single_global_label": "ignore",
      "unannotated": "error",
      "unconnected_wire_endpoint": "warning",
      "unit_value_mismatch": "error",
      "unresolved_variable": "error",
      "wire_dangling": "error"
    }
  },
  "libraries": {
    "pinned_footprint_libs": [],
    "pinned_symbol_libs": []
  },
  "meta": {
    "filename": "sdi-mipi-video-converter.kicad_pro",
    "version": 3
  },
  "net_settings": {
    "classes": [
      {
        "bus_width": 12,
        "clearance": 0.1,
        "diff_pair_gap": 0.2,
        "diff_pair_via_gap": 0.25,
        "diff_pair_width": 0.182,
        "line_style": 0,
        "microvia_diameter": 0.3,
        "microvia_drill": 0.1,
        "name": "Default",
        "pcb_color": "rgba(0, 0, 0, 0.000)",
        "priority": 2147483647,
        "schematic_color": "rgba(0, 0, 0, 0.000)",
        "track_width": 0.15,
        "via_diameter": 0.45,
        "via_drill": 0.1,
        "wire_width": 6
      },
      {
        "bus_width": 12,
        "clearance": 0.1,
        "diff_pair_gap": 0.3,
        "diff_pair_via_gap": 0.25,
        "diff_pair_width": 0.15,
        "line_style": 0,
        "microvia_diameter": 0.3,
        "microvia_drill": 0.1,
        "name": "100Ohm-diff_CSI",
        "pcb_color": "rgba(0, 0, 0, 0.000)",
        "priority": 0,
        "schematic_color": "rgba(0, 0, 0, 0.000)",
        "track_width": 0.15,
        "via_diameter": 0.45,
        "via_drill": 0.1,
        "wire_width": 6
      },
      {
        "bus_width": 12,
        "clearance": 0.1,
        "diff_pair_gap": 0.3,
        "diff_pair_via_gap": 0.25,
        "diff_pair_width": 0.2,
        "line_style": 0,
        "microvia_diameter": 0.3,
        "microvia_drill": 0.1,
        "name": "100Ohm-diff_SDO",
        "pcb_color": "rgba(0, 0, 0, 0.000)",
        "priority": 1,
        "schematic_color": "rgba(0, 0, 0, 0.000)",
        "track_width": 0.15,
        "via_diameter": 0.45,
        "via_drill": 0.1,
        "wire_width": 6
      },
      {
        "bus_width": 12,
        "clearance": 0.1,
        "diff_pair_gap": 0.8,
        "diff_pair_via_gap": 0.25,
        "diff_pair_width": 0.4,
        "line_style": 0,
        "microvia_diameter": 0.3,
        "microvia_drill": 0.1,
        "name": "140Ohm-diff_SDI",
        "pcb_color": "rgba(0, 0, 0, 0.000)",
        "priority": 2,
        "schematic_color": "rgba(0, 0, 0, 0.000)",
        "track_width": 0.3,
        "via_diameter": 0.45,
        "via_drill": 0.1,
        "wire_width": 6
      },
      {
        "bus_width": 12,
        "clearance": 0.1,
        "diff_pair_gap": 0.2,
        "diff_pair_via_gap": 0.25,
        "diff_pair_width": 0.15,
        "line_style": 0,
        "microvia_diameter": 0.3,
        "microvia_drill": 0.1,
        "name": "50Ohm-se_DDR3",
        "pcb_color": "rgb(62, 255, 1)",
        "priority": 3,
        "schematic_color": "rgba(0, 0, 0, 0.000)",
        "track_width": 0.15,
        "via_diameter": 0.45,
        "via_drill": 0.1,
        "wire_width": 6
      },
      {
        "bus_width": 12,
        "clearance": 0.1,
        "diff_pair_gap": 0.2,
        "diff_pair_via_gap": 0.25,
        "diff_pair_width": 0.182,
        "line_style": 0,
        "microvia_diameter": 0.3,
        "microvia_drill": 0.1,
        "name": "50Ohm-se_SDI_D",
        "pcb_color": "rgba(0, 0, 0, 0.000)",
        "priority": 4,
        "schematic_color": "rgba(0, 0, 0, 0.000)",
        "track_width": 0.2,
        "via_diameter": 0.45,
        "via_drill": 0.1,
        "wire_width": 6
      },
      {
        "bus_width": 12,
        "clearance": 0.1,
        "diff_pair_gap": 0.5,
        "diff_pair_via_gap": 0.25,
        "diff_pair_width": 0.1,
        "line_style": 0,
        "microvia_diameter": 0.3,
        "microvia_drill": 0.1,
        "name": "75Ohm-se_SDI",
        "pcb_color": "rgba(0, 0, 0, 0.000)",
        "priority": 5,
        "schematic_color": "rgba(0, 0, 0, 0.000)",
        "track_width": 0.45,
        "via_diameter": 0.45,
        "via_drill": 0.1,
        "wire_width": 6
      },
      {
        "bus_width": 12,
        "clearance": 0.1,
        "diff_pair_gap": 0.2,
        "diff_pair_via_gap": 0.25,
        "diff_pair_width": 0.15,
        "line_style": 0,
        "microvia_diameter": 0.3,
        "microvia_drill": 0.1,
        "name": "90Ohm-diff_DDR3",
        "pcb_color": "rgba(0, 0, 0, 0.000)",
        "priority": 6,
        "schematic_color": "rgba(0, 0, 0, 0.000)",
        "track_width": 0.15,
        "via_diameter": 0.45,
        "via_drill": 0.1,
        "wire_width": 6
      }
    ],
    "meta": {
      "version": 4
    },
    "net_colors": null,
    "netclass_assignments": null,
    "netclass_patterns": [
      {
        "netclass": "100Ohm-diff_CSI",
        "pattern": "/Peripherals/MIPI0_CLK_N"
      },
      {
        "netclass": "100Ohm-diff_CSI",
        "pattern": "/Peripherals/MIPI0_CLK_P"
      },
      {
        "netclass": "100Ohm-diff_CSI",
        "pattern": "/Peripherals/MIPI0_D0_N"
      },
      {
        "netclass": "100Ohm-diff_CSI",
        "pattern": "/Peripherals/MIPI0_D0_P"
      },
      {
        "netclass": "100Ohm-diff_CSI",
        "pattern": "/Peripherals/MIPI0_D1_N"
      },
      {
        "netclass": "100Ohm-diff_CSI",
        "pattern": "/Peripherals/MIPI0_D1_P"
      },
      {
        "netclass": "100Ohm-diff_CSI",
        "pattern": "/Peripherals/MIPI0_D2_N"
      },
      {
        "netclass": "100Ohm-diff_CSI",
        "pattern": "/Peripherals/MIPI0_D2_P"
      },
      {
        "netclass": "100Ohm-diff_CSI",
        "pattern": "/Peripherals/MIPI0_D3_N"
      },
      {
        "netclass": "100Ohm-diff_CSI",
        "pattern": "/Peripherals/MIPI0_D3_P"
      },
      {
        "netclass": "100Ohm-diff_CSI",
        "pattern": "/Peripherals/MIPI1_CLK_N"
      },
      {
        "netclass": "100Ohm-diff_CSI",
        "pattern": "/Peripherals/MIPI1_CLK_P"
      },
      {
        "netclass": "100Ohm-diff_CSI",
        "pattern": "/Peripherals/MIPI1_D0_N"
      },
      {
        "netclass": "100Ohm-diff_CSI",
        "pattern": "/Peripherals/MIPI1_D0_P"
      },
      {
        "netclass": "100Ohm-diff_CSI",
        "pattern": "/Peripherals/MIPI1_D1_N"
      },
      {
        "netclass": "100Ohm-diff_CSI",
        "pattern": "/Peripherals/MIPI1_D1_P"
      },
      {
        "netclass": "100Ohm-diff_CSI",
        "pattern": "/Peripherals/MIPI1_D2_N"
      },
      {
        "netclass": "100Ohm-diff_CSI",
        "pattern": "/Peripherals/MIPI1_D2_P"
      },
      {
        "netclass": "100Ohm-diff_CSI",
        "pattern": "/Peripherals/MIPI1_D3_N"
      },
      {
        "netclass": "100Ohm-diff_CSI",
        "pattern": "/Peripherals/MIPI1_D3_P"
      },
      {
        "netclass": "100Ohm-diff_CSI",
        "pattern": "/Peripherals/MIPI2_CLK_N"
      },
      {
        "netclass": "100Ohm-diff_CSI",
        "pattern": "/Peripherals/MIPI2_CLK_P"
      },
      {
        "netclass": "100Ohm-diff_CSI",
        "pattern": "/Peripherals/MIPI2_D0_N"
      },
      {
        "netclass": "100Ohm-diff_CSI",
        "pattern": "/Peripherals/MIPI2_D0_P"
      },
      {
        "netclass": "100Ohm-diff_CSI",
        "pattern": "/Peripherals/MIPI2_D1_N"
      },
      {
        "netclass": "100Ohm-diff_CSI",
        "pattern": "/Peripherals/MIPI2_D1_P"
      },
      {
        "netclass": "100Ohm-diff_CSI",
        "pattern": "/Peripherals/MIPI2_D2_N"
      },
      {
        "netclass": "100Ohm-diff_CSI",
        "pattern": "/Peripherals/MIPI2_D2_P"
      },
      {
        "netclass": "100Ohm-diff_CSI",
        "pattern": "/Peripherals/MIPI2_D3_N"
      },
      {
        "netclass": "100Ohm-diff_CSI",
        "pattern": "/Peripherals/MIPI2_D3_P"
      },
      {
        "netclass": "100Ohm-diff_SDO",
        "pattern": "/SDI/SDO_N"
      },
      {
        "netclass": "100Ohm-diff_SDO",
        "pattern": "/SDI/SDO_P"
      },
      {
        "netclass": "140Ohm-diff_SDI",
        "pattern": "/SDI/AGC_N"
      },
      {
        "netclass": "140Ohm-diff_SDI",
        "pattern": "/SDI/AGC_P"
      },
      {
        "netclass": "140Ohm-diff_SDI",
        "pattern": "/SDI/SDI_N"
      },
      {
        "netclass": "140Ohm-diff_SDI",
        "pattern": "/SDI/SDI_N2"
      },
      {
        "netclass": "140Ohm-diff_SDI",
        "pattern": "/SDI/SDI_OUT_N"
      },
      {
        "netclass": "140Ohm-diff_SDI",
        "pattern": "/SDI/SDI_OUT_P"
      },
      {
        "netclass": "140Ohm-diff_SDI",
        "pattern": "/SDI/SDI_P"
      },
      {
        "netclass": "50Ohm-se_DDR3",
        "pattern": "/DDR3/DDR3_A0"
      },
      {
        "netclass": "50Ohm-se_DDR3",
        "pattern": "/DDR3/DDR3_A1"
      },
      {
        "netclass": "50Ohm-se_DDR3",
        "pattern": "/DDR3/DDR3_A10"
      },
      {
        "netclass": "50Ohm-se_DDR3",
        "pattern": "/DDR3/DDR3_A11"
      },
      {
        "netclass": "50Ohm-se_DDR3",
        "pattern": "/DDR3/DDR3_A12"
      },
      {
        "netclass": "50Ohm-se_DDR3",
        "pattern": "/DDR3/DDR3_A13"
      },
      {
        "netclass": "50Ohm-se_DDR3",
        "pattern": "/DDR3/DDR3_A2"
      },
      {
        "netclass": "50Ohm-se_DDR3",
        "pattern": "/DDR3/DDR3_A3"
      },
      {
        "netclass": "50Ohm-se_DDR3",
        "pattern": "/DDR3/DDR3_A4"
      },
      {
        "netclass": "50Ohm-se_DDR3",
        "pattern": "/DDR3/DDR3_A5"
      },
      {
        "netclass": "50Ohm-se_DDR3",
        "pattern": "/DDR3/DDR3_A6"
      },
      {
        "netclass": "50Ohm-se_DDR3",
        "pattern": "/DDR3/DDR3_A7"
      },
      {
        "netclass": "50Ohm-se_DDR3",
        "pattern": "/DDR3/DDR3_A8"
      },
      {
        "netclass": "50Ohm-se_DDR3",
        "pattern": "/DDR3/DDR3_A9"
      },
      {
        "netclass": "50Ohm-se_DDR3",
        "pattern": "/DDR3/DDR3_BA0"
      },
      {
        "netclass": "50Ohm-se_DDR3",
        "pattern": "/DDR3/DDR3_BA1"
      },
      {
        "netclass": "50Ohm-se_DDR3",
        "pattern": "/DDR3/DDR3_BA2"
      },
      {
        "netclass": "50Ohm-se_DDR3",
        "pattern": "/DDR3/DDR3_CKE"
      },
      {
        "netclass": "50Ohm-se_DDR3",
        "pattern": "/DDR3/DDR3_DQ0"
      },
      {
        "netclass": "50Ohm-se_DDR3",
        "pattern": "/DDR3/DDR3_DQ1"
      },
      {
        "netclass": "50Ohm-se_DDR3",
        "pattern": "/DDR3/DDR3_DQ10"
      },
      {
        "netclass": "50Ohm-se_DDR3",
        "pattern": "/DDR3/DDR3_DQ11"
      },
      {
        "netclass": "50Ohm-se_DDR3",
        "pattern": "/DDR3/DDR3_DQ12"
      },
      {
        "netclass": "50Ohm-se_DDR3",
        "pattern": "/DDR3/DDR3_DQ13"
      },
      {
        "netclass": "50Ohm-se_DDR3",
        "pattern": "/DDR3/DDR3_DQ14"
      },
      {
        "netclass": "50Ohm-se_DDR3",
        "pattern": "/DDR3/DDR3_DQ15"
      },
      {
        "netclass": "50Ohm-se_DDR3",
        "pattern": "/DDR3/DDR3_DQ2"
      },
      {
        "netclass": "50Ohm-se_DDR3",
        "pattern": "/DDR3/DDR3_DQ3"
      },
      {
        "netclass": "50Ohm-se_DDR3",
        "pattern": "/DDR3/DDR3_DQ4"
      },
      {
        "netclass": "50Ohm-se_DDR3",
        "pattern": "/DDR3/DDR3_DQ5"
      },
      {
        "netclass": "50Ohm-se_DDR3",
        "pattern": "/DDR3/DDR3_DQ6"
      },
      {
        "netclass": "50Ohm-se_DDR3",
        "pattern": "/DDR3/DDR3_DQ7"
      },
      {
        "netclass": "50Ohm-se_DDR3",
        "pattern": "/DDR3/DDR3_DQ8"
      },
      {
        "netclass": "50Ohm-se_DDR3",
        "pattern": "/DDR3/DDR3_DQ9"
      },
      {
        "netclass": "50Ohm-se_DDR3",
        "pattern": "/DDR3/DDR3_LDM"
      },
      {
        "netclass": "50Ohm-se_DDR3",
        "pattern": "/DDR3/DDR3_ODT"
      },
      {
        "netclass": "50Ohm-se_DDR3",
        "pattern": "/DDR3/DDR3_UDM"
      },
      {
        "netclass": "50Ohm-se_DDR3",
        "pattern": "/DDR3/~{DDR3_CAS}"
      },
      {
        "netclass": "50Ohm-se_DDR3",
        "pattern": "/DDR3/~{DDR3_CS}"
      },
      {
        "netclass": "50Ohm-se_DDR3",
        "pattern": "/DDR3/~{DDR3_RAS}"
      },
      {
        "netclass": "50Ohm-se_DDR3",
        "pattern": "/DDR3/~{DDR3_RESET}"
      },
      {
        "netclass": "50Ohm-se_DDR3",
        "pattern": "/DDR3/~{DDR3_WE}"
      },
      {
        "netclass": "50Ohm-se_SDI_D",
        "pattern": "/SDI/SDI_D0"
      },
      {
        "netclass": "50Ohm-se_SDI_D",
        "pattern": "/SDI/SDI_D1"
      },
      {
        "netclass": "50Ohm-se_SDI_D",
        "pattern": "/SDI/SDI_D10"
      },
      {
        "netclass": "50Ohm-se_SDI_D",
        "pattern": "/SDI/SDI_D11"
      },
      {
        "netclass": "50Ohm-se_SDI_D",
        "pattern": "/SDI/SDI_D12"
      },
      {
        "netclass": "50Ohm-se_SDI_D",
        "pattern": "/SDI/SDI_D13"
      },
      {
        "netclass": "50Ohm-se_SDI_D",
        "pattern": "/SDI/SDI_D14"
      },
      {
        "netclass": "50Ohm-se_SDI_D",
        "pattern": "/SDI/SDI_D15"
      },
      {
        "netclass": "50Ohm-se_SDI_D",
        "pattern": "/SDI/SDI_D16"
      },
      {
        "netclass": "50Ohm-se_SDI_D",
        "pattern": "/SDI/SDI_D17"
      },
      {
        "netclass": "50Ohm-se_SDI_D",
        "pattern": "/SDI/SDI_D18"
      },
      {
        "netclass": "50Ohm-se_SDI_D",
        "pattern": "/SDI/SDI_D19"
      },
      {
        "netclass": "50Ohm-se_SDI_D",
        "pattern": "/SDI/SDI_D2"
      },
      {
        "netclass": "50Ohm-se_SDI_D",
        "pattern": "/SDI/SDI_D3"
      },
      {
        "netclass": "50Ohm-se_SDI_D",
        "pattern": "/SDI/SDI_D4"
      },
      {
        "netclass": "50Ohm-se_SDI_D",
        "pattern": "/SDI/SDI_D5"
      },
      {
        "netclass": "50Ohm-se_SDI_D",
        "pattern": "/SDI/SDI_D6"
      },
      {
        "netclass": "50Ohm-se_SDI_D",
        "pattern": "/SDI/SDI_D7"
      },
      {
        "netclass": "50Ohm-se_SDI_D",
        "pattern": "/SDI/SDI_D8"
      },
      {
        "netclass": "50Ohm-se_SDI_D",
        "pattern": "/SDI/SDI_D9"
      },
      {
        "netclass": "50Ohm-se_SDI_D",
        "pattern": "/SDI/SDI_PCLK"
      },
      {
        "netclass": "75Ohm-se_SDI",
        "pattern": "/SDI/SDI_IN"
      },
      {
        "netclass": "75Ohm-se_SDI",
        "pattern": "/SDI/SDI_IN_F"
      },
      {
        "netclass": "75Ohm-se_SDI",
        "pattern": "/SDI/SDI_OUT"
      },
      {
        "netclass": "75Ohm-se_SDI",
        "pattern": "/SDI/SDI_OUT_F2"
      },
      {
        "netclass": "90Ohm-diff_DDR3",
        "pattern": "/DDR3/DDR3_CK_N"
      },
      {
        "netclass": "90Ohm-diff_DDR3",
        "pattern": "/DDR3/DDR3_CK_P"
      },
      {
        "netclass": "90Ohm-diff_DDR3",
        "pattern": "/DDR3/DDR3_LDQS_N"
      },
      {
        "netclass": "90Ohm-diff_DDR3",
        "pattern": "/DDR3/DDR3_LDQS_P"
      },
      {
        "netclass": "90Ohm-diff_DDR3",
        "pattern": "/DDR3/DDR3_UDQS_N"
      },
      {
        "netclass": "90Ohm-diff_DDR3",
        "pattern": "/DDR3/DDR3_UDQS_P"
      }
    ]
  },
  "pcbnew": {
    "last_paths": {
      "gencad": "",
      "idf": "",
      "netlist": "",
      "plot": "",
      "pos_files": "",
      "specctra_dsn": "",
      "step": "",
      "svg": "",
      "vrml": ""
    },
    "page_layout_descr_file": ""
  },
  "schematic": {
    "annotate_start_num": 0,
    "bom_export_filename": "${PROJECTNAME}.csv",
    "bom_fmt_presets": [],
    "bom_fmt_settings": {
      "field_delimiter": ",",
      "keep_line_breaks": false,
      "keep_tabs": false,
      "name": "CSV",
      "ref_delimiter": ",",
      "ref_range_delimiter": "",
      "string_delimiter": "\""
    },
    "bom_presets": [],
    "bom_settings": {
      "exclude_dnp": false,
      "fields_ordered": [
        {
          "group_by": false,
          "label": "Reference",
          "name": "Reference",
          "show": true
        },
        {
          "group_by": false,
          "label": "Qty",
          "name": "${QUANTITY}",
          "show": true
        },
        {
          "group_by": true,
          "label": "Value",
          "name": "Value",
          "show": true
        },
        {
          "group_by": true,
          "label": "DNP",
          "name": "${DNP}",
          "show": true
        },
        {
          "group_by": true,
          "label": "Exclude from BOM",
          "name": "${EXCLUDE_FROM_BOM}",
          "show": true
        },
        {
          "group_by": true,
          "label": "Exclude from Board",
          "name": "${EXCLUDE_FROM_BOARD}",
          "show": true
        },
        {
          "group_by": true,
          "label": "Footprint",
          "name": "Footprint",
          "show": true
        },
        {
          "group_by": false,
          "label": "Datasheet",
          "name": "Datasheet",
          "show": true
        }
      ],
      "filter_string": "",
      "group_symbols": true,
      "include_excluded_from_bom": true,
      "name": "Default Editing",
      "sort_asc": true,
      "sort_field": "Reference"
    },
    "connection_grid_size": 50.0,
    "drawing": {
      "dashed_lines_dash_length_ratio": 12.0,
      "dashed_lines_gap_length_ratio": 3.0,
      "default_line_thickness": 6.0,
      "default_text_size": 50.0,
      "field_names": [],
      "intersheets_ref_own_page": false,
      "intersheets_ref_prefix": "",
      "intersheets_ref_short": false,
      "intersheets_ref_show": false,
      "intersheets_ref_suffix": "",
      "junction_size_choice": 3,
      "label_size_ratio": 0.375,
      "operating_point_overlay_i_precision": 3,
      "operating_point_overlay_i_range": "~A",
      "operating_point_overlay_v_precision": 3,
      "operating_point_overlay_v_range": "~V",
      "overbar_offset_ratio": 1.23,
      "pin_symbol_size": 25.0,
      "text_offset_ratio": 0.15
    },
    "legacy_lib_dir": "",
    "legacy_lib_list": [],
    "meta": {
      "version": 1
    },
    "net_format_name": "",
    "ngspice": {
      "fix_include_paths": true,
      "fix_passive_vals": false,
      "meta": {
        "version": 0
      },
      "model_mode": 0,
      "workbook_filename": ""
    },
    "page_layout_descr_file": "",
    "plot_directory": "./doc",
    "space_save_all_events": true,
    "spice_adjust_passive_values": false,
    "spice_current_sheet_as_root": false,
    "spice_external_command": "spice \"%I\"",
    "spice_model_current_sheet_as_root": true,
    "spice_save_all_currents": false,
    "spice_save_all_dissipations": false,
    "spice_save_all_voltages": false,
    "subpart_first_id": 65,
    "subpart_id_separator": 0
  },
  "sheets": [
    [
      "",
      "Root"
    ],
    [
      "",
      "Power Supply"
    ],
    [
      "",
      "DDR3"
    ],
    [
      "",
      "SDI"
    ],
    [
      "",
      "FPGA"
    ],
    [
      "",
      "Peripherals"
    ],
    [
      "",
      "FPGA Power"
    ]
  ],
  "text_variables": {}
}
